# BASEBOARD_FAB2 (Tioga Pass) — schematic netlist excerpt (pin names and nets, part order shuffled) for the footprints in the layout excerpt that follows; sources: Cadence DE-HDL packaged netlist, KiCad conversion of Wiwynn_Tioga_Pass_MB.brd

R4D14  RES  27.4 1% CHIP  pkg 0402  page 103 : A = CLK_100M_CPU0_BCLK2_R_DN ; B = CLK_100M_CPU0_BCLK2_DN
C7A22  CAP  0.220UF 16V 10% X7R  pkg 0402  page 219 : A = VR_PVDDQ_DEF_PH2_BOOT ; B = VR_PVDDQ_DEF_PH2_PHASE
R9W17  RES  2.0K 1% CHIP  pkg 0402  page 248 : A = P3V3_STBY ; B = SMB_PEHPCPU0_STBY_LVC3_R_SCL

(kicad_pcb
	(version 20260206)
	(generator "pcbnew")
	(generator_version "10.0")
	(general
		(thickness 1.6)
		(legacy_teardrops no)
	)
	(paper "A4")
	(title_block
		(title "Wiwynn_Tioga_Pass_MB.brd")
		(comment 1 "Tioga Pass / footprints 781-783 of 4770")
	)
	(layers
		(0 "F.Cu" signal "TOP")
		(4 "In1.Cu" signal "L2GND")
		(6 "In2.Cu" signal "L3")
		(8 "In3.Cu" signal "L4GND")
		(10 "In4.Cu" signal "L5")
		(12 "In5.Cu" signal "L6GND")
		(14 "In6.Cu" signal "L7VCC")
		(16 "In7.Cu" signal "L8VCC")
		(18 "In8.Cu" signal "L9GND")
		(20 "In9.Cu" signal "L10")
		(22 "In10.Cu" signal "L11GND")
		(24 "In11.Cu" signal "L12")
		(26 "In12.Cu" signal "L13GND")
		(2 "B.Cu" signal "BOTTOM")
		(9 "F.Adhes" user "F.Adhesive")
		(11 "B.Adhes" user "B.Adhesive")
		(13 "F.Paste" user "Package Geometry/Pastemask Top")
		(15 "B.Paste" user "Package Geometry/Pastemask Bottom")
		(5 "F.SilkS" user "Ref Des/Silkscreen Top")
		(7 "B.SilkS" user "Ref Des/Silkscreen Bottom")
		(1 "F.Mask" user "Board Geometry/Soldermask Top")
		(3 "B.Mask" user "Board Geometry/Soldermask Bottom")
		(17 "Dwgs.User" user "User.Drawings")
		(19 "Cmts.User" user "User.Comments")
		(21 "Eco1.User" user "User.Eco1")
		(23 "Eco2.User" user "User.Eco2")
		(25 "Edge.Cuts" user "Board Geometry/Outline")
		(27 "Margin" user)
		(31 "F.CrtYd" user "Package Geometry/Place Bound Top")
		(29 "B.CrtYd" user "Package Geometry/Place Bound Bottom")
		(35 "F.Fab" user "Ref Des/Assembly Top")
		(33 "B.Fab" user "Ref Des/Assembly Bottom")
	)
	(footprint ""
		(layer "F.Cu")
		(at 175.387 -82.677 90)
		(property "Reference" "R4D14"
			(at 0 0 90)
			(layer "F.SilkS")
			(hide yes)
			(effects
				(font
					(size 1.27 1.27)
				)
			)
		)
		(property "Value" ""
			(at 0 0 90)
			(layer "F.Fab")
			(effects
				(font
					(size 1.27 1.27)
				)
			)
		)
		(duplicate_pad_numbers_are_jumpers no)
		(fp_poly
			(pts
				(xy -0.2794 -0.1016) (xy 0.2794 -0.1016) (xy 0.2794 0.9906) (xy -0.2794 0.9906)
			)
			(stroke
				(width 0)
				(type default)
			)
			(fill no)
			(layer "F.CrtYd")
		)
		(fp_line
			(start 0.2794 -0.1016)
			(end -0.2794 -0.1016)
			(stroke
				(width 0.1)
				(type default)
			)
			(layer "F.Fab")
		)
		(fp_line
			(start -0.2794 -0.1016)
			(end -0.2794 0.9906)
			(stroke
				(width 0.1)
				(type default)
			)
			(layer "F.Fab")
		)
		(fp_line
			(start 0.2794 0.9906)
			(end 0.2794 -0.1016)
			(stroke
				(width 0.1)
				(type default)
			)
			(layer "F.Fab")
		)
		(fp_line
			(start -0.2794 0.9906)
			(end 0.2794 0.9906)
			(stroke
				(width 0.1)
				(type default)
			)
			(layer "F.Fab")
		)
		(pad "1" smd rect
			(at 0 0 90)
			(size 0.508 0.508)
			(layers "F.Cu" "F.Mask" "F.Paste")
			(net "CLK_100M_CPU0_BCLK2_R_DN")
		)
		(pad "2" smd rect
			(at 0 0.889 90)
			(size 0.508 0.508)
			(layers "F.Cu" "F.Mask" "F.Paste")
			(net "CLK_100M_CPU0_BCLK2_DN")
		)
		(zone
			(layer "F.Cu")
			(hatch none 0.5)
			(connect_pads
				(clearance 0)
			)
			(min_thickness 0.25)
			(keepout
				(tracks allowed)
				(vias not_allowed)
				(pads allowed)
				(copperpour not_allowed)
				(footprints allowed)
			)
			(placement
				(enabled no)
				(sheetname "")
			)
			(fill
				(thermal_gap 0.5)
				(thermal_bridge_width 0.5)
				(island_removal_mode 0)
			)
			(polygon
				(pts
					(xy 175.641 -82.423) (xy 175.641 -82.931) (xy 176.022 -82.931) (xy 176.022 -82.423)
				)
			)
		)
		(zone
			(layer "F.Cu")
			(hatch none 0.5)
			(connect_pads
				(clearance 0)
			)
			(min_thickness 0.25)
			(keepout
				(tracks not_allowed)
				(vias allowed)
				(pads allowed)
				(copperpour not_allowed)
				(footprints allowed)
			)
			(placement
				(enabled no)
				(sheetname "")
			)
			(fill
				(thermal_gap 0.5)
				(thermal_bridge_width 0.5)
				(island_removal_mode 0)
			)
			(polygon
				(pts
					(xy 176.022 -82.423) (xy 176.022 -82.931) (xy 175.641 -82.931) (xy 175.641 -82.423)
				)
			)
		)
	)
	(footprint ""
		(layer "F.Cu")
		(at 352.759518 -143.483076 -90)
		(property "Reference" "C7A22"
			(at 0 0 270)
			(layer "F.SilkS")
			(hide yes)
			(effects
				(font
					(size 1.27 1.27)
				)
			)
		)
		(property "Value" ""
			(at 0 0 270)
			(layer "F.Fab")
			(effects
				(font
					(size 1.27 1.27)
				)
			)
		)
		(duplicate_pad_numbers_are_jumpers no)
		(fp_poly
			(pts
				(xy 0.3048 -0.1016) (xy 0.3048 0.9906) (xy -0.3048 0.9906) (xy -0.3048 -0.1016)
			)
			(stroke
				(width 0)
				(type default)
			)
			(fill no)
			(layer "F.CrtYd")
		)
		(fp_line
			(start -0.3048 0.9906)
			(end 0.3048 0.9906)
			(stroke
				(width 0.1)
				(type default)
			)
			(layer "F.Fab")
		)
		(fp_line
			(start 0.3048 0.9906)
			(end 0.3048 -0.1016)
			(stroke
				(width 0.1)
				(type default)
			)
			(layer "F.Fab")
		)
		(fp_line
			(start -0.3048 -0.1016)
			(end -0.3048 0.9906)
			(stroke
				(width 0.1)
				(type default)
			)
			(layer "F.Fab")
		)
		(fp_line
			(start 0.3048 -0.1016)
			(end -0.3048 -0.1016)
			(stroke
				(width 0.1)
				(type default)
			)
			(layer "F.Fab")
		)
		(pad "1" smd rect
			(at 0 0 270)
			(size 0.508 0.508)
			(layers "F.Cu" "F.Mask" "F.Paste")
			(net "VR_PVDDQ_DEF_PH2_BOOT")
		)
		(pad "2" smd rect
			(at 0 0.889 270)
			(size 0.508 0.508)
			(layers "F.Cu" "F.Mask" "F.Paste")
			(net "VR_PVDDQ_DEF_PH2_PHASE")
		)
		(zone
			(layer "F.Cu")
			(hatch none 0.5)
			(connect_pads
				(clearance 0)
			)
			(min_thickness 0.25)
			(keepout
				(tracks not_allowed)
				(vias allowed)
				(pads allowed)
				(copperpour not_allowed)
				(footprints allowed)
			)
			(placement
				(enabled no)
				(sheetname "")
			)
			(fill
				(thermal_gap 0.5)
				(thermal_bridge_width 0.5)
				(island_removal_mode 0)
			)
			(polygon
				(pts
					(xy 352.124518 -143.737076) (xy 352.124518 -143.229076) (xy 352.505518 -143.229076) (xy 352.505518 -143.737076)
				)
			)
		)
		(zone
			(layer "F.Cu")
			(hatch none 0.5)
			(connect_pads
				(clearance 0)
			)
			(min_thickness 0.25)
			(keepout
				(tracks allowed)
				(vias not_allowed)
				(pads allowed)
				(copperpour not_allowed)
				(footprints allowed)
			)
			(placement
				(enabled no)
				(sheetname "")
			)
			(fill
				(thermal_gap 0.5)
				(thermal_bridge_width 0.5)
				(island_removal_mode 0)
			)
			(polygon
				(pts
					(xy 352.505518 -143.737076) (xy 352.505518 -143.229076) (xy 352.124518 -143.229076) (xy 352.124518 -143.737076)
				)
			)
		)
	)
	(footprint ""
		(layer "F.Cu")
		(at 419.5445 -113.03 90)
		(property "Reference" "R9W17"
			(at -0.8382 -0.67818 90)
			(unlocked yes)
			(layer "F.SilkS")
			(effects
				(font
					(size 0.4064 0.254)
					(thickness 0.1524)
				)
				(justify left)
			)
		)
		(property "Value" ""
			(at 0 0 90)
			(layer "F.Fab")
			(effects
				(font
					(size 1.27 1.27)
				)
			)
		)
		(duplicate_pad_numbers_are_jumpers no)
		(fp_poly
			(pts
				(xy -0.2794 -0.1016) (xy 0.2794 -0.1016) (xy 0.2794 0.9906) (xy -0.2794 0.9906)
			)
			(stroke
				(width 0)
				(type default)
			)
			(fill no)
			(layer "F.CrtYd")
		)
		(fp_line
			(start 0.2794 -0.1016)
			(end -0.2794 -0.1016)
			(stroke
				(width 0.1)
				(type default)
			)
			(layer "F.Fab")
		)
		(fp_line
			(start -0.2794 -0.1016)
			(end -0.2794 0.9906)
			(stroke
				(width 0.1)
				(type default)
			)
			(layer "F.Fab")
		)
		(fp_line
			(start 0.2794 0.9906)
			(end 0.2794 -0.1016)
			(stroke
				(width 0.1)
				(type default)
			)
			(layer "F.Fab")
		)
		(fp_line
			(start -0.2794 0.9906)
			(end 0.2794 0.9906)
			(stroke
				(width 0.1)
				(type default)
			)
			(layer "F.Fab")
		)
		(pad "1" smd rect
			(at 0 0 90)
			(size 0.508 0.508)
			(layers "F.Cu" "F.Mask" "F.Paste")
			(net "P3V3_STBY")
		)
		(pad "2" smd rect
			(at 0 0.889 90)
			(size 0.508 0.508)
			(layers "F.Cu" "F.Mask" "F.Paste")
			(net "SMB_PEHPCPU0_STBY_LVC3_R_SCL")
		)
		(zone
			(layer "F.Cu")
			(hatch none 0.5)
			(connect_pads
				(clearance 0)
			)
			(min_thickness 0.25)
			(keepout
				(tracks allowed)
				(vias not_allowed)
				(pads allowed)
				(copperpour not_allowed)
				(footprints allowed)
			)
			(placement
				(enabled no)
				(sheetname "")
			)
			(fill
				(thermal_gap 0.5)
				(thermal_bridge_width 0.5)
				(island_removal_mode 0)
			)
			(polygon
				(pts
					(xy 419.7985 -112.776) (xy 419.7985 -113.284) (xy 420.1795 -113.284) (xy 420.1795 -112.776)
				)
			)
		)
		(zone
			(layer "F.Cu")
			(hatch none 0.5)
			(connect_pads
				(clearance 0)
			)
			(min_thickness 0.25)
			(keepout
				(tracks not_allowed)
				(vias allowed)
				(pads allowed)
				(copperpour not_allowed)
				(footprints allowed)
			)
			(placement
				(enabled no)
				(sheetname "")
			)
			(fill
				(thermal_gap 0.5)
				(thermal_bridge_width 0.5)
				(island_removal_mode 0)
			)
			(polygon
				(pts
					(xy 420.1795 -112.776) (xy 420.1795 -113.284) (xy 419.7985 -113.284) (xy 419.7985 -112.776)
				)
			)
		)
	)
)
